FILE_TYPE=LIBRARY_PARTS;
primitive 'MC74VHC1G07DFT2G';
  pin
    'VCC':
      PIN_NUMBER='(5)';
      PINUSE='POWER';
      NO_LOAD_CHECK='Both';
      NO_IO_CHECK='Both';
      NO_ASSERT_CHECK='TRUE';
      NO_DIR_CHECK='TRUE';
      ALLOW_CONNECT='TRUE';
    'IN_A':
      PIN_NUMBER='(2)';
      INPUT_LOAD='(-0.01,0.01)';
    'GND':
      PIN_NUMBER='(3)';
      PINUSE='POWER';
      NO_LOAD_CHECK='Both';
      NO_IO_CHECK='Both';
      NO_ASSERT_CHECK='TRUE';
      NO_DIR_CHECK='TRUE';
      ALLOW_CONNECT='TRUE';
    'OUT_Y':
      PIN_NUMBER='(4)';
      OUTPUT_LOAD='(1.0,-1.0)';
    'NC1':
      PIN_NUMBER='(1)';
      OUTPUT_TYPE='(TS,TS)';
      INPUT_LOAD='(-0.01,0.01)';
      OUTPUT_LOAD='(1.0,-1.0)';
  end_pin;
  body
    PART_NAME='MC74VHC1G07DFT2G';
    BODY_NAME='MC74VHC1G07DFT2G';
    PHYS_DES_PREFIX='U';
    CLASS='IC';
  end_body;
end_primitive;

END.
